FILE_TYPE = MACRO_DRAWING;
SET COLOR_WIRE YELLOW;
SET COLOR_PROP ORANGE;
SET COLOR_DOT WHITE;
SET COLOR_ARC YELLOW;
SET COLOR_BODY GREEN;
SET COLOR_NOTE PURPLE;
SET PROP_DISPLAY VALUE;
SET PAGE_NUMBER P242;
FORCEADD OFFPAGE..1
(-6925 4250);
PAINT AQUA (-6925 4250);
FORCEPROP 2 LAST $XR1 223 
J 0
(-7177 4214);
DISPLAY 0.638298 (-7177 4214);
PAINT MONO (-7177 4214);
FORCEPROP 2 LAST $XR0 182 
J 0
(-7177 4250);
DISPLAY 0.638298 (-7177 4250);
PAINT MONO (-7177 4250);
FORCEPROP 2 LAST PATH I1
J 0
(-7175 4300);
DISPLAY 1.021277 (-7175 4300);
DISPLAY INVISIBLE (-7175 4300);
FORCEPROP 1 LAST COMMENT_BODY TRUE
J 0
(-6800 4150);
DISPLAY 0.872340 (-6800 4150);
PAINT GREEN (-6800 4150);
DISPLAY INVISIBLE (-6800 4150);
FORCEPROP 1 LAST OFFPAGE TRUE
J 0
(-6600 4125);
DISPLAY 0.872340 (-6600 4125);
PAINT AQUA (-6600 4125);
DISPLAY INVISIBLE (-6600 4125);
FORCEPROP 2 LAST CDS_LIB standard
J 0
(-6925 4250);
DISPLAY INVISIBLE (-6925 4250);
FORCEADD UNIVERSAL_GND..1
(-5775 7825);
FORCEPROP 3 LASTPIN (-5775 7875) SIG_NAME GND\g
J 0
(-5765 7885);
DISPLAY 0.659574 (-5765 7885);
PAINT MONO (-5765 7885);
DISPLAY INVISIBLE (-5765 7885);
FORCEPROP 1 LAST PATH I10
J 0
(-5700 7825);
DISPLAY 0.872340 (-5700 7825);
PAINT AQUA (-5700 7825);
DISPLAY INVISIBLE (-5700 7825);
FORCEPROP 1 LAST HDL_POWER GND
J 1
(-5750 7750);
DISPLAY 0.872340 (-5750 7750);
PAINT GREEN (-5750 7750);
DISPLAY INVISIBLE (-5750 7750);
FORCEPROP 2 LAST CDS_LIB logical_power
J 0
(-5775 7825);
DISPLAY INVISIBLE (-5775 7825);
FORCEADD Q_LED..1
R 2
(-4725 4575);
FORCEPROP 1 LAST PART_NUMBER BEBL0172Z00
J 0
(-4825 4350);
DISPLAY 0.574468 (-4825 4350);
PAINT GREEN (-4825 4350);
DISPLAY INVISIBLE (-4825 4350);
FORCEPROP 0 LAST PACK_TYPE SMLF
J 0
(-4825 4400);
DISPLAY 0.638298 (-4825 4400);
FORCEPROP 2 LAST MANUF_PN LTST-C281TBKT-5A
J 0
(-4825 4300);
DISPLAY 0.638298 (-4825 4300);
FORCEPROP 1 LAST MATERIAL IC
J 0
(-4700 4400);
DISPLAY 0.723404 (-4700 4400);
PAINT GREEN (-4700 4400);
FORCEPROP 2 LAST COLOR LED_BLUE
J 0
(-4825 4450);
DISPLAY 0.638298 (-4825 4450);
FORCEPROP 1 LAST LOCATION D94
J 0
(-4825 4500);
DISPLAY 0.723404 (-4825 4500);
PAINT GREEN (-4825 4500);
FORCEPROP 0 LASTPIN (-4575 4575) $PN A
J 0
(-4565 4585);
DISPLAY 0.808511 (-4565 4585);
FORCEPROP 0 LASTPIN (-4875 4575) $PN C
J 2
(-4885 4585);
DISPLAY 0.808511 (-4885 4585);
FORCEPROP 2 LAST CDS_LIB pure_quanta
J 0
(-4725 4575);
DISPLAY INVISIBLE (-4725 4575);
FORCEPROP 1 LAST NEEDS_NO_SIZE TRUE
J 2
(-4703 4597);
DISPLAY 0.468085 (-4703 4597);
PAINT GREEN (-4703 4597);
DISPLAY INVISIBLE (-4703 4597);
FORCEPROP 1 LAST PATH I11
J 2
(-4850 4655);
DISPLAY 0.723404 (-4850 4655);
PAINT GREEN (-4850 4655);
DISPLAY INVISIBLE (-4850 4655);
FORCEPROP 0 LAST $SEC 1
J 0
(-4825 4550);
DISPLAY INVISIBLE (-4825 4550);
FORCEPROP 0 LAST CDS_SEC 1
J 0
(-4825 4550);
DISPLAY INVISIBLE (-4825 4550);
FORCEADD Q_RES..1
(-3375 4575);
FORCEPROP 1 LAST PART_NUMBER CS11302FB03
J 0
(-3600 4675);
DISPLAY 0.638298 (-3600 4675);
DISPLAY INVISIBLE (-3600 4675);
FORCEPROP 1 LAST MATERIAL CHIP
J 0
(-3525 4525);
DISPLAY 0.638298 (-3525 4525);
FORCEPROP 1 LAST VALUE 130
J 2
(-3175 4575);
DISPLAY 0.638298 (-3175 4575);
FORCEPROP 1 LAST TOLERANCE 1%
J 0
(-3150 4575);
DISPLAY 0.638298 (-3150 4575);
FORCEPROP 1 LAST WATTAGE 1/16W
J 2
(-3225 4525);
DISPLAY 0.638298 (-3225 4525);
FORCEPROP 1 LAST PACK_TYPE 0402LF
J 0
(-3075 4575);
DISPLAY 0.638298 (-3075 4575);
FORCEPROP 1 LAST $LOCATION R3073
J 0
(-3425 4625);
DISPLAY 0.978723 (-3425 4625);
FORCEPROP 1 LASTPIN (-3475 4575) $PN 1
J 0
(-3463 4587);
DISPLAY 0.787234 (-3463 4587);
PAINT MONO (-3463 4587);
FORCEPROP 1 LASTPIN (-3275 4575) $PN 2
J 0
(-3313 4587);
DISPLAY 0.787234 (-3313 4587);
PAINT MONO (-3313 4587);
FORCEPROP 1 LAST PATH I12
J 0
(-3425 4725);
DISPLAY 0.978723 (-3425 4725);
PAINT WHITE (-3425 4725);
DISPLAY INVISIBLE (-3425 4725);
FORCEPROP 2 LAST CDS_LIB pure_quanta
J 0
(-3375 4575);
DISPLAY INVISIBLE (-3375 4575);
FORCEPROP 0 LAST CDS_LOCATION R3073
J 0
(-3425 4675);
DISPLAY 1.021277 (-3425 4675);
DISPLAY INVISIBLE (-3425 4675);
FORCEPROP 0 LAST $SEC 1
J 0
(-3425 4675);
DISPLAY 0.680851 (-3425 4675);
PAINT MONO (-3425 4675);
DISPLAY INVISIBLE (-3425 4675);
FORCEPROP 0 LAST CDS_SEC 1
J 0
(-3425 4675);
DISPLAY 1.021277 (-3425 4675);
DISPLAY INVISIBLE (-3425 4675);
FORCEADD Q_LED..1
R 2
(-4750 5900);
FORCEPROP 1 LAST PART_NUMBER BEBL0172Z00
J 0
(-4850 5675);
DISPLAY 0.574468 (-4850 5675);
PAINT GREEN (-4850 5675);
DISPLAY INVISIBLE (-4850 5675);
FORCEPROP 2 LAST MANUF_PN LTST-C281TBKT-5A
J 0
(-4850 5625);
DISPLAY 0.638298 (-4850 5625);
FORCEPROP 2 LAST COLOR LED_BLUE
J 0
(-4850 5775);
DISPLAY 0.638298 (-4850 5775);
FORCEPROP 1 LAST MATERIAL IC
J 0
(-4725 5725);
DISPLAY 0.723404 (-4725 5725);
PAINT GREEN (-4725 5725);
FORCEPROP 0 LAST PACK_TYPE SMLF
J 0
(-4850 5725);
DISPLAY 0.638298 (-4850 5725);
FORCEPROP 1 LAST LOCATION D93
J 0
(-4850 5825);
DISPLAY 0.723404 (-4850 5825);
PAINT GREEN (-4850 5825);
FORCEPROP 0 LASTPIN (-4600 5900) $PN A
J 0
(-4590 5910);
DISPLAY 0.808511 (-4590 5910);
FORCEPROP 0 LASTPIN (-4900 5900) $PN C
J 2
(-4910 5910);
DISPLAY 0.808511 (-4910 5910);
FORCEPROP 1 LAST PATH I13
J 2
(-4875 5980);
DISPLAY 0.723404 (-4875 5980);
PAINT GREEN (-4875 5980);
DISPLAY INVISIBLE (-4875 5980);
FORCEPROP 1 LAST NEEDS_NO_SIZE TRUE
J 2
(-4728 5922);
DISPLAY 0.468085 (-4728 5922);
PAINT GREEN (-4728 5922);
DISPLAY INVISIBLE (-4728 5922);
FORCEPROP 2 LAST CDS_LIB pure_quanta
J 0
(-4750 5900);
DISPLAY INVISIBLE (-4750 5900);
FORCEPROP 0 LAST $SEC 1
J 0
(-4850 5875);
DISPLAY INVISIBLE (-4850 5875);
FORCEPROP 0 LAST CDS_SEC 1
J 0
(-4850 5875);
DISPLAY INVISIBLE (-4850 5875);
FORCEADD Q_RES..1
(-3325 5900);
FORCEPROP 1 LAST PART_NUMBER CS11302FB03
J 0
(-3550 6000);
DISPLAY 0.638298 (-3550 6000);
DISPLAY INVISIBLE (-3550 6000);
FORCEPROP 1 LAST TOLERANCE 1%
J 0
(-3100 5900);
DISPLAY 0.638298 (-3100 5900);
FORCEPROP 1 LAST WATTAGE 1/16W
J 2
(-3175 5850);
DISPLAY 0.638298 (-3175 5850);
FORCEPROP 1 LAST VALUE 130
J 2
(-3125 5900);
DISPLAY 0.638298 (-3125 5900);
FORCEPROP 1 LAST MATERIAL CHIP
J 0
(-3475 5850);
DISPLAY 0.638298 (-3475 5850);
FORCEPROP 1 LAST PACK_TYPE 0402LF
J 0
(-3025 5900);
DISPLAY 0.638298 (-3025 5900);
FORCEPROP 1 LAST $LOCATION R3074
J 0
(-3375 5950);
DISPLAY 0.978723 (-3375 5950);
FORCEPROP 1 LASTPIN (-3425 5900) $PN 1
J 0
(-3413 5912);
DISPLAY 0.787234 (-3413 5912);
PAINT MONO (-3413 5912);
FORCEPROP 1 LASTPIN (-3225 5900) $PN 2
J 0
(-3263 5912);
DISPLAY 0.787234 (-3263 5912);
PAINT MONO (-3263 5912);
FORCEPROP 1 LAST PATH I14
J 0
(-3375 6050);
DISPLAY 0.978723 (-3375 6050);
PAINT WHITE (-3375 6050);
DISPLAY INVISIBLE (-3375 6050);
FORCEPROP 2 LAST CDS_LIB pure_quanta
J 0
(-3325 5900);
DISPLAY INVISIBLE (-3325 5900);
FORCEPROP 0 LAST CDS_LOCATION R3074
J 0
(-3375 6000);
DISPLAY 1.021277 (-3375 6000);
DISPLAY INVISIBLE (-3375 6000);
FORCEPROP 0 LAST $SEC 1
J 0
(-3375 6000);
DISPLAY 0.680851 (-3375 6000);
PAINT MONO (-3375 6000);
DISPLAY INVISIBLE (-3375 6000);
FORCEPROP 0 LAST CDS_SEC 1
J 0
(-3375 6000);
DISPLAY 1.021277 (-3375 6000);
DISPLAY INVISIBLE (-3375 6000);
FORCEADD Q_RES..1
(-3375 7125);
FORCEPROP 1 LAST PART_NUMBER CS11302FB03
J 0
(-3600 7225);
DISPLAY 0.638298 (-3600 7225);
DISPLAY INVISIBLE (-3600 7225);
FORCEPROP 1 LAST PACK_TYPE 0402LF
J 0
(-3075 7125);
DISPLAY 0.638298 (-3075 7125);
FORCEPROP 1 LAST TOLERANCE 1%
J 0
(-3150 7125);
DISPLAY 0.638298 (-3150 7125);
FORCEPROP 1 LAST VALUE 130
J 2
(-3175 7125);
DISPLAY 0.638298 (-3175 7125);
FORCEPROP 1 LAST MATERIAL CHIP
J 0
(-3525 7075);
DISPLAY 0.638298 (-3525 7075);
FORCEPROP 1 LAST WATTAGE 1/16W
J 2
(-3225 7075);
DISPLAY 0.638298 (-3225 7075);
FORCEPROP 1 LAST $LOCATION R3072
J 0
(-3425 7175);
DISPLAY 0.978723 (-3425 7175);
FORCEPROP 1 LASTPIN (-3475 7125) $PN 1
J 0
(-3463 7137);
DISPLAY 0.787234 (-3463 7137);
PAINT MONO (-3463 7137);
FORCEPROP 1 LASTPIN (-3275 7125) $PN 2
J 0
(-3313 7137);
DISPLAY 0.787234 (-3313 7137);
PAINT MONO (-3313 7137);
FORCEPROP 1 LAST PATH I15
J 0
(-3425 7275);
DISPLAY 0.978723 (-3425 7275);
PAINT WHITE (-3425 7275);
DISPLAY INVISIBLE (-3425 7275);
FORCEPROP 2 LAST CDS_LIB pure_quanta
J 0
(-3375 7125);
DISPLAY INVISIBLE (-3375 7125);
FORCEPROP 0 LAST CDS_LOCATION R3072
J 0
(-3425 7225);
DISPLAY 1.021277 (-3425 7225);
DISPLAY INVISIBLE (-3425 7225);
FORCEPROP 0 LAST $SEC 1
J 0
(-3425 7225);
DISPLAY 0.680851 (-3425 7225);
PAINT MONO (-3425 7225);
DISPLAY INVISIBLE (-3425 7225);
FORCEPROP 0 LAST CDS_SEC 1
J 0
(-3425 7225);
DISPLAY 1.021277 (-3425 7225);
DISPLAY INVISIBLE (-3425 7225);
FORCEADD OFFPAGE..1
(-6925 8125);
PAINT AQUA (-6925 8125);
FORCEPROP 2 LAST $XR2 222 
J 0
(-7177 8161);
DISPLAY 0.638298 (-7177 8161);
PAINT MONO (-7177 8161);
FORCEPROP 2 LAST $XR1 194 
J 0
(-7177 8089);
DISPLAY 0.638298 (-7177 8089);
PAINT MONO (-7177 8089);
FORCEPROP 2 LAST $XR0 263 
J 0
(-7177 8125);
DISPLAY 0.638298 (-7177 8125);
PAINT MONO (-7177 8125);
FORCEPROP 2 LAST PATH I16
J 0
(-7175 8175);
DISPLAY 1.021277 (-7175 8175);
DISPLAY INVISIBLE (-7175 8175);
FORCEPROP 1 LAST COMMENT_BODY TRUE
J 0
(-6800 8025);
DISPLAY 0.872340 (-6800 8025);
PAINT GREEN (-6800 8025);
DISPLAY INVISIBLE (-6800 8025);
FORCEPROP 1 LAST OFFPAGE TRUE
J 0
(-6600 8000);
DISPLAY 0.872340 (-6600 8000);
PAINT AQUA (-6600 8000);
DISPLAY INVISIBLE (-6600 8000);
FORCEPROP 2 LAST CDS_LIB standard
J 0
(-6925 8125);
DISPLAY INVISIBLE (-6925 8125);
FORCEADD MOSFET_NCH_DUAL..1
(-5825 8175);
FORCEPROP 1 LAST PART_NUMBER BAM138K0003
J 0
(-5674 8089);
DISPLAY 0.723404 (-5674 8089);
PAINT GREEN (-5674 8089);
DISPLAY INVISIBLE (-5674 8089);
FORCEPROP 1 LAST MATERIAL IC
J 0
(-5674 8024);
DISPLAY 0.723404 (-5674 8024);
PAINT GREEN (-5674 8024);
FORCEPROP 2 LAST PART_TYPE SMLF
J 0
(-5650 8250);
DISPLAY 1.021277 (-5650 8250);
FORCEPROP 2 LAST VALUE PJT138K
J 0
(-5650 8200);
DISPLAY 1.021277 (-5650 8200);
FORCEPROP 1 LAST LOCATION Q76
J 0
(-5674 8149);
DISPLAY 0.723404 (-5674 8149);
PAINT GREEN (-5674 8149);
FORCEPROP 0 LASTPIN (-5775 8375) $PN 6
R 1
J 0
(-5785 8385);
DISPLAY 0.808511 (-5785 8385);
FORCEPROP 0 LASTPIN (-6025 8125) $PN 2
J 2
(-6035 8135);
DISPLAY 0.808511 (-6035 8135);
FORCEPROP 0 LASTPIN (-5775 7975) $PN 1
R 1
J 2
(-5785 7965);
DISPLAY 0.808511 (-5785 7965);
FORCEPROP 1 LAST PATH I17
J 0
(-5825 8175);
DISPLAY 0.723404 (-5825 8175);
PAINT GREEN (-5825 8175);
DISPLAY INVISIBLE (-5825 8175);
FORCEPROP 1 LAST NEEDS_NO_SIZE TRUE
J 0
(-5825 8174);
DISPLAY 0.468085 (-5825 8174);
PAINT GREEN (-5825 8174);
DISPLAY INVISIBLE (-5825 8174);
FORCEPROP 1 LAST CDS_LMAN_SYM_OUTLINE -150,150,150,-150
J 0
(-5825 8175);
DISPLAY 0.468085 (-5825 8175);
PAINT GREEN (-5825 8175);
DISPLAY INVISIBLE (-5825 8175);
FORCEPROP 2 LAST CDS_LIB pure_quanta
J 0
(-5825 8175);
DISPLAY INVISIBLE (-5825 8175);
FORCEPROP 0 LAST $SEC 1
J 0
(-5650 8300);
DISPLAY INVISIBLE (-5650 8300);
FORCEPROP 0 LAST CDS_SEC 1
J 0
(-5650 8300);
DISPLAY INVISIBLE (-5650 8300);
FORCEADD Q_LED..1
R 2
(-4750 8450);
FORCEPROP 1 LAST PART_NUMBER BEBL0172Z00
J 0
(-4850 8225);
DISPLAY 0.574468 (-4850 8225);
PAINT GREEN (-4850 8225);
DISPLAY INVISIBLE (-4850 8225);
FORCEPROP 1 LAST MATERIAL IC
J 0
(-4725 8275);
DISPLAY 0.723404 (-4725 8275);
PAINT GREEN (-4725 8275);
FORCEPROP 2 LAST COLOR LED_BLUE
J 0
(-4850 8325);
DISPLAY 0.638298 (-4850 8325);
FORCEPROP 0 LAST PACK_TYPE SMLF
J 0
(-4850 8275);
DISPLAY 0.638298 (-4850 8275);
FORCEPROP 2 LAST MANUF_PN LTST-C281TBKT-5A
J 0
(-4850 8175);
DISPLAY 0.638298 (-4850 8175);
FORCEPROP 1 LAST LOCATION D91
J 0
(-4850 8375);
DISPLAY 0.723404 (-4850 8375);
PAINT GREEN (-4850 8375);
FORCEPROP 0 LASTPIN (-4600 8450) $PN A
J 0
(-4590 8460);
DISPLAY 0.808511 (-4590 8460);
FORCEPROP 0 LASTPIN (-4900 8450) $PN C
J 2
(-4910 8460);
DISPLAY 0.808511 (-4910 8460);
FORCEPROP 1 LAST PATH I18
J 2
(-4875 8530);
DISPLAY 0.723404 (-4875 8530);
PAINT GREEN (-4875 8530);
DISPLAY INVISIBLE (-4875 8530);
FORCEPROP 2 LAST CDS_LIB pure_quanta
J 0
(-4750 8450);
DISPLAY INVISIBLE (-4750 8450);
FORCEPROP 1 LAST NEEDS_NO_SIZE TRUE
J 2
(-4728 8472);
DISPLAY 0.468085 (-4728 8472);
PAINT GREEN (-4728 8472);
DISPLAY INVISIBLE (-4728 8472);
FORCEPROP 0 LAST $SEC 1
J 0
(-4850 8425);
DISPLAY INVISIBLE (-4850 8425);
FORCEPROP 0 LAST CDS_SEC 1
J 0
(-4850 8425);
DISPLAY INVISIBLE (-4850 8425);
FORCEADD Q_RES..1
(-3400 8450);
FORCEPROP 1 LAST PART_NUMBER CS11302FB03
J 0
(-3625 8550);
DISPLAY 0.638298 (-3625 8550);
DISPLAY INVISIBLE (-3625 8550);
FORCEPROP 1 LAST WATTAGE 1/16W
J 2
(-3250 8400);
DISPLAY 0.638298 (-3250 8400);
FORCEPROP 1 LAST MATERIAL CHIP
J 0
(-3550 8400);
DISPLAY 0.638298 (-3550 8400);
FORCEPROP 1 LAST VALUE 130
J 2
(-3200 8450);
DISPLAY 0.638298 (-3200 8450);
FORCEPROP 1 LAST TOLERANCE 1%
J 0
(-3175 8450);
DISPLAY 0.638298 (-3175 8450);
FORCEPROP 1 LAST PACK_TYPE 0402LF
J 0
(-3100 8450);
DISPLAY 0.638298 (-3100 8450);
FORCEPROP 1 LAST $LOCATION R3071
J 0
(-3450 8500);
DISPLAY 0.978723 (-3450 8500);
FORCEPROP 1 LASTPIN (-3500 8450) $PN 1
J 0
(-3488 8462);
DISPLAY 0.787234 (-3488 8462);
PAINT MONO (-3488 8462);
FORCEPROP 1 LASTPIN (-3300 8450) $PN 2
J 0
(-3338 8462);
DISPLAY 0.787234 (-3338 8462);
PAINT MONO (-3338 8462);
FORCEPROP 1 LAST PATH I19
J 0
(-3450 8600);
DISPLAY 0.978723 (-3450 8600);
PAINT WHITE (-3450 8600);
DISPLAY INVISIBLE (-3450 8600);
FORCEPROP 2 LAST CDS_LIB pure_quanta
J 0
(-3400 8450);
DISPLAY INVISIBLE (-3400 8450);
FORCEPROP 0 LAST CDS_LOCATION R3071
J 0
(-3450 8550);
DISPLAY 1.021277 (-3450 8550);
DISPLAY INVISIBLE (-3450 8550);
FORCEPROP 0 LAST $SEC 1
J 0
(-3450 8550);
DISPLAY 0.680851 (-3450 8550);
PAINT MONO (-3450 8550);
DISPLAY INVISIBLE (-3450 8550);
FORCEPROP 0 LAST CDS_SEC 1
J 0
(-3450 8550);
DISPLAY 1.021277 (-3450 8550);
DISPLAY INVISIBLE (-3450 8550);
FORCEADD OFFPAGE..1
(-6925 5575);
PAINT AQUA (-6925 5575);
FORCEPROP 2 LAST $XR2 223 
J 0
(-7177 5611);
DISPLAY 0.638298 (-7177 5611);
PAINT MONO (-7177 5611);
FORCEPROP 2 LAST $XR1 219 
J 0
(-7177 5539);
DISPLAY 0.638298 (-7177 5539);
PAINT MONO (-7177 5539);
FORCEPROP 2 LAST $XR0 215 
J 0
(-7177 5575);
DISPLAY 0.638298 (-7177 5575);
PAINT MONO (-7177 5575);
FORCEPROP 2 LAST PATH I2
J 0
(-7175 5650);
DISPLAY 1.021277 (-7175 5650);
DISPLAY INVISIBLE (-7175 5650);
FORCEPROP 1 LAST COMMENT_BODY TRUE
J 0
(-6800 5475);
DISPLAY 0.872340 (-6800 5475);
PAINT GREEN (-6800 5475);
DISPLAY INVISIBLE (-6800 5475);
FORCEPROP 1 LAST OFFPAGE TRUE
J 0
(-6600 5450);
DISPLAY 0.872340 (-6600 5450);
PAINT AQUA (-6600 5450);
DISPLAY INVISIBLE (-6600 5450);
FORCEPROP 2 LAST CDS_LIB standard
J 0
(-6925 5575);
DISPLAY INVISIBLE (-6925 5575);
FORCEADD UNIVERSAL_POWER..1
(-2775 4725);
FORCEPROP 3 LASTPIN (-2775 4675) SIG_NAME P3V3_AUX\g
J 0
(-2765 4685);
DISPLAY 0.659574 (-2765 4685);
PAINT MONO (-2765 4685);
DISPLAY INVISIBLE (-2765 4685);
FORCEPROP 1 LAST HDL_POWER P3V3_AUX
J 1
(-2775 4775);
DISPLAY 0.723404 (-2775 4775);
PAINT GREEN (-2775 4775);
FORCEPROP 1 LAST PATH I20
J 0
(-2725 4750);
DISPLAY 0.872340 (-2725 4750);
PAINT AQUA (-2725 4750);
DISPLAY INVISIBLE (-2725 4750);
FORCEPROP 2 LAST CDS_LIB logical_power
J 0
(-2775 4725);
DISPLAY INVISIBLE (-2775 4725);
FORCEADD UNIVERSAL_POWER..1
(-2725 6075);
FORCEPROP 3 LASTPIN (-2725 6025) SIG_NAME P3V3_AUX\g
J 0
(-2715 6035);
DISPLAY 0.659574 (-2715 6035);
PAINT MONO (-2715 6035);
DISPLAY INVISIBLE (-2715 6035);
FORCEPROP 1 LAST HDL_POWER P3V3_AUX
J 1
(-2725 6125);
DISPLAY 0.723404 (-2725 6125);
PAINT GREEN (-2725 6125);
FORCEPROP 1 LAST PATH I23
J 0
(-2675 6100);
DISPLAY 0.872340 (-2675 6100);
PAINT AQUA (-2675 6100);
DISPLAY INVISIBLE (-2675 6100);
FORCEPROP 2 LAST CDS_LIB logical_power
J 0
(-2725 6075);
DISPLAY INVISIBLE (-2725 6075);
FORCEADD OFFPAGE..1
(-2150 6800);
PAINT AQUA (-2150 6800);
FORCEPROP 2 LAST $XR1 224 
J 0
(-2522 6800);
DISPLAY 0.638298 (-2522 6800);
PAINT MONO (-2522 6800);
FORCEPROP 2 LAST $XR0 214 
J 0
(-2402 6800);
DISPLAY 0.638298 (-2402 6800);
PAINT MONO (-2402 6800);
FORCEPROP 2 LAST PATH I24
J 0
(-2425 6850);
DISPLAY 1.021277 (-2425 6850);
DISPLAY INVISIBLE (-2425 6850);
FORCEPROP 1 LAST COMMENT_BODY TRUE
J 0
(-2025 6700);
DISPLAY 0.872340 (-2025 6700);
PAINT GREEN (-2025 6700);
DISPLAY INVISIBLE (-2025 6700);
FORCEPROP 1 LAST OFFPAGE TRUE
J 0
(-1825 6675);
DISPLAY 0.872340 (-1825 6675);
PAINT AQUA (-1825 6675);
DISPLAY INVISIBLE (-1825 6675);
FORCEPROP 2 LAST CDS_LIB standard
J 0
(-2150 6800);
DISPLAY INVISIBLE (-2150 6800);
FORCEADD UNIVERSAL_POWER..1
(-2775 7250);
FORCEPROP 3 LASTPIN (-2775 7200) SIG_NAME P3V3_AUX\g
J 0
(-2765 7210);
DISPLAY 0.659574 (-2765 7210);
PAINT MONO (-2765 7210);
DISPLAY INVISIBLE (-2765 7210);
FORCEPROP 1 LAST HDL_POWER P3V3_AUX
J 1
(-2775 7300);
DISPLAY 0.723404 (-2775 7300);
PAINT GREEN (-2775 7300);
FORCEPROP 1 LAST PATH I25
J 0
(-2725 7275);
DISPLAY 0.872340 (-2725 7275);
PAINT AQUA (-2725 7275);
DISPLAY INVISIBLE (-2725 7275);
FORCEPROP 2 LAST CDS_LIB logical_power
J 0
(-2775 7250);
DISPLAY INVISIBLE (-2775 7250);
FORCEADD MOSFET_NCH_DUAL..2
(-1050 6850);
FORCEPROP 1 LAST PART_NUMBER BAM138K0003
J 0
(-899 6756);
DISPLAY 0.723404 (-899 6756);
PAINT BLUE (-899 6756);
DISPLAY INVISIBLE (-899 6756);
FORCEPROP 1 LAST MATERIAL IC
J 0
(-899 6701);
DISPLAY 0.723404 (-899 6701);
PAINT SKYBLUE (-899 6701);
FORCEPROP 2 LAST PART_TYPE SMLF
J 0
(-875 6925);
DISPLAY 1.021277 (-875 6925);
FORCEPROP 2 LAST VALUE PJT138K
J 0
(-875 6875);
DISPLAY 0.723404 (-875 6875);
PAINT SKYBLUE (-875 6875);
FORCEPROP 1 LAST LOCATION Q78
J 0
(-899 6826);
DISPLAY 0.723404 (-899 6826);
PAINT AQUA (-899 6826);
FORCEPROP 2 LASTPIN (-1000 7050) $PN 3
R 1
J 0
(-1010 7060);
DISPLAY 0.723404 (-1010 7060);
PAINT MONO (-1010 7060);
FORCEPROP 2 LASTPIN (-1250 6800) $PN 5
J 2
(-1260 6810);
DISPLAY 0.723404 (-1260 6810);
PAINT MONO (-1260 6810);
FORCEPROP 2 LASTPIN (-1000 6650) $PN 4
R 1
J 2
(-1010 6640);
DISPLAY 0.723404 (-1010 6640);
PAINT MONO (-1010 6640);
FORCEPROP 1 LAST PATH I26
J 0
(-900 6700);
DISPLAY 0.723404 (-900 6700);
PAINT GREEN (-900 6700);
DISPLAY INVISIBLE (-900 6700);
FORCEPROP 2 LAST SEC_TYPE 
J 0
(-875 6975);
DISPLAY 1.021277 (-875 6975);
DISPLAY INVISIBLE (-875 6975);
FORCEPROP 2 LAST CDS_LIB pure_quanta
J 0
(-1050 6850);
DISPLAY INVISIBLE (-1050 6850);
FORCEPROP 1 LAST NEEDS_NO_SIZE TRUE
J 0
(-900 6741);
DISPLAY 0.468085 (-900 6741);
PAINT GREEN (-900 6741);
DISPLAY INVISIBLE (-900 6741);
FORCEPROP 1 LAST CDS_LMAN_SYM_OUTLINE -150,150,150,-150
J 0
(-1050 6850);
DISPLAY 0.468085 (-1050 6850);
PAINT GREEN (-1050 6850);
DISPLAY INVISIBLE (-1050 6850);
FORCEPROP 2 LAST SEC 2
J 0
(-875 6975);
DISPLAY 0.680851 (-875 6975);
PAINT MONO (-875 6975);
DISPLAY INVISIBLE (-875 6975);
FORCEADD UNIVERSAL_GND..1
(-1000 6500);
FORCEPROP 3 LASTPIN (-1000 6550) SIG_NAME GND\g
J 0
(-990 6560);
DISPLAY 0.659574 (-990 6560);
PAINT MONO (-990 6560);
DISPLAY INVISIBLE (-990 6560);
FORCEPROP 1 LAST PATH I28
J 0
(-925 6500);
DISPLAY 0.872340 (-925 6500);
PAINT AQUA (-925 6500);
DISPLAY INVISIBLE (-925 6500);
FORCEPROP 1 LAST HDL_POWER GND
J 1
(-975 6425);
DISPLAY 0.872340 (-975 6425);
PAINT GREEN (-975 6425);
DISPLAY INVISIBLE (-975 6425);
FORCEPROP 2 LAST CDS_LIB logical_power
J 0
(-1000 6500);
DISPLAY INVISIBLE (-1000 6500);
FORCEADD MOSFET_NCH_DUAL..2
(-5825 4300);
FORCEPROP 1 LAST PART_NUMBER BAM138K0003
J 0
(-5674 4206);
DISPLAY 0.723404 (-5674 4206);
PAINT BLUE (-5674 4206);
DISPLAY INVISIBLE (-5674 4206);
FORCEPROP 2 LAST PART_TYPE SMLF
J 0
(-5650 4375);
DISPLAY 1.021277 (-5650 4375);
FORCEPROP 1 LAST MATERIAL IC
J 0
(-5674 4151);
DISPLAY 0.723404 (-5674 4151);
PAINT SKYBLUE (-5674 4151);
FORCEPROP 2 LAST VALUE PJT138K
J 0
(-5650 4325);
DISPLAY 0.723404 (-5650 4325);
PAINT SKYBLUE (-5650 4325);
FORCEPROP 1 LAST LOCATION Q77
J 0
(-5674 4276);
DISPLAY 0.723404 (-5674 4276);
PAINT AQUA (-5674 4276);
FORCEPROP 2 LASTPIN (-5775 4500) $PN 3
R 1
J 0
(-5785 4510);
DISPLAY 0.723404 (-5785 4510);
PAINT MONO (-5785 4510);
FORCEPROP 2 LASTPIN (-6025 4250) $PN 5
J 2
(-6035 4260);
DISPLAY 0.723404 (-6035 4260);
PAINT MONO (-6035 4260);
FORCEPROP 2 LASTPIN (-5775 4100) $PN 4
R 1
J 2
(-5785 4090);
DISPLAY 0.723404 (-5785 4090);
PAINT MONO (-5785 4090);
FORCEPROP 1 LAST PATH I3
J 0
(-5675 4150);
DISPLAY 0.723404 (-5675 4150);
PAINT GREEN (-5675 4150);
DISPLAY INVISIBLE (-5675 4150);
FORCEPROP 2 LAST SEC_TYPE 
J 0
(-5650 4425);
DISPLAY 1.021277 (-5650 4425);
DISPLAY INVISIBLE (-5650 4425);
FORCEPROP 2 LAST CDS_LIB pure_quanta
J 0
(-5825 4300);
DISPLAY INVISIBLE (-5825 4300);
FORCEPROP 1 LAST NEEDS_NO_SIZE TRUE
J 0
(-5675 4191);
DISPLAY 0.468085 (-5675 4191);
PAINT GREEN (-5675 4191);
DISPLAY INVISIBLE (-5675 4191);
FORCEPROP 1 LAST CDS_LMAN_SYM_OUTLINE -150,150,150,-150
J 0
(-5825 4300);
DISPLAY 0.468085 (-5825 4300);
PAINT GREEN (-5825 4300);
DISPLAY INVISIBLE (-5825 4300);
FORCEPROP 2 LAST SEC 2
J 0
(-5650 4425);
DISPLAY 0.680851 (-5650 4425);
PAINT MONO (-5650 4425);
DISPLAY INVISIBLE (-5650 4425);
FORCEADD UNIVERSAL_GND..1
(-1000 7825);
FORCEPROP 3 LASTPIN (-1000 7875) SIG_NAME GND\g
J 0
(-990 7885);
DISPLAY 0.659574 (-990 7885);
PAINT MONO (-990 7885);
DISPLAY INVISIBLE (-990 7885);
FORCEPROP 1 LAST PATH I30
J 0
(-925 7825);
DISPLAY 0.872340 (-925 7825);
PAINT AQUA (-925 7825);
DISPLAY INVISIBLE (-925 7825);
FORCEPROP 1 LAST HDL_POWER GND
J 1
(-975 7750);
DISPLAY 0.872340 (-975 7750);
PAINT GREEN (-975 7750);
DISPLAY INVISIBLE (-975 7750);
FORCEPROP 2 LAST CDS_LIB logical_power
J 0
(-1000 7825);
DISPLAY INVISIBLE (-1000 7825);
FORCEADD Q_LED..1
R 2
(25 7125);
FORCEPROP 1 LAST PART_NUMBER BEBL0172Z00
J 0
(-75 6900);
DISPLAY 0.574468 (-75 6900);
PAINT GREEN (-75 6900);
DISPLAY INVISIBLE (-75 6900);
FORCEPROP 2 LAST MANUF_PN LTST-C281TBKT-5A
J 0
(-75 6850);
DISPLAY 0.638298 (-75 6850);
FORCEPROP 0 LAST PACK_TYPE SMLF
J 0
(-75 6950);
DISPLAY 0.638298 (-75 6950);
FORCEPROP 2 LAST COLOR LED_BLUE
J 0
(-75 7000);
DISPLAY 0.638298 (-75 7000);
FORCEPROP 1 LAST MATERIAL IC
J 0
(50 6950);
DISPLAY 0.723404 (50 6950);
PAINT GREEN (50 6950);
FORCEPROP 1 LAST LOCATION D96
J 0
(-75 7050);
DISPLAY 0.723404 (-75 7050);
PAINT GREEN (-75 7050);
FORCEPROP 0 LASTPIN (175 7125) $PN A
J 0
(185 7135);
DISPLAY 0.808511 (185 7135);
FORCEPROP 0 LASTPIN (-125 7125) $PN C
J 2
(-135 7135);
DISPLAY 0.808511 (-135 7135);
FORCEPROP 1 LAST PATH I31
J 2
(-100 7205);
DISPLAY 0.723404 (-100 7205);
PAINT GREEN (-100 7205);
DISPLAY INVISIBLE (-100 7205);
FORCEPROP 2 LAST CDS_LIB pure_quanta
J 0
(25 7125);
DISPLAY INVISIBLE (25 7125);
FORCEPROP 1 LAST NEEDS_NO_SIZE TRUE
J 2
(47 7147);
DISPLAY 0.468085 (47 7147);
PAINT GREEN (47 7147);
DISPLAY INVISIBLE (47 7147);
FORCEPROP 0 LAST $SEC 1
J 0
(-75 7100);
DISPLAY INVISIBLE (-75 7100);
FORCEPROP 0 LAST CDS_SEC 1
J 0
(-75 7100);
DISPLAY INVISIBLE (-75 7100);
FORCEADD UNIVERSAL_POWER..1
(-2750 8600);
FORCEPROP 3 LASTPIN (-2750 8550) SIG_NAME P3V3_AUX\g
J 0
(-2740 8560);
DISPLAY 0.659574 (-2740 8560);
PAINT MONO (-2740 8560);
DISPLAY INVISIBLE (-2740 8560);
FORCEPROP 1 LAST HDL_POWER P3V3_AUX
J 1
(-2750 8650);
DISPLAY 0.723404 (-2750 8650);
PAINT GREEN (-2750 8650);
FORCEPROP 1 LAST PATH I32
J 0
(-2700 8625);
DISPLAY 0.872340 (-2700 8625);
PAINT AQUA (-2700 8625);
DISPLAY INVISIBLE (-2700 8625);
FORCEPROP 2 LAST CDS_LIB logical_power
J 0
(-2750 8600);
DISPLAY INVISIBLE (-2750 8600);
FORCEADD OFFPAGE..1
(-2150 8125);
PAINT AQUA (-2150 8125);
FORCEPROP 2 LAST $XR1 223 
J 0
(-2522 8125);
DISPLAY 0.638298 (-2522 8125);
PAINT MONO (-2522 8125);
FORCEPROP 2 LAST $XR0 182 
J 0
(-2402 8125);
DISPLAY 0.638298 (-2402 8125);
PAINT MONO (-2402 8125);
FORCEPROP 2 LAST PATH I33
J 0
(-2425 8175);
DISPLAY 1.021277 (-2425 8175);
DISPLAY INVISIBLE (-2425 8175);
FORCEPROP 1 LAST COMMENT_BODY TRUE
J 0
(-2025 8025);
DISPLAY 0.872340 (-2025 8025);
PAINT GREEN (-2025 8025);
DISPLAY INVISIBLE (-2025 8025);
FORCEPROP 1 LAST OFFPAGE TRUE
J 0
(-1825 8000);
DISPLAY 0.872340 (-1825 8000);
PAINT AQUA (-1825 8000);
DISPLAY INVISIBLE (-1825 8000);
FORCEPROP 2 LAST CDS_LIB standard
J 0
(-2150 8125);
DISPLAY INVISIBLE (-2150 8125);
FORCEADD MOSFET_NCH_DUAL..1
(-1050 8175);
FORCEPROP 1 LAST PART_NUMBER BAM138K0003
J 0
(-899 8089);
DISPLAY 0.723404 (-899 8089);
PAINT GREEN (-899 8089);
DISPLAY INVISIBLE (-899 8089);
FORCEPROP 2 LAST VALUE PJT138K
J 0
(-875 8200);
DISPLAY 1.021277 (-875 8200);
FORCEPROP 2 LAST PART_TYPE SMLF
J 0
(-875 8250);
DISPLAY 1.021277 (-875 8250);
FORCEPROP 1 LAST MATERIAL IC
J 0
(-899 8024);
DISPLAY 0.723404 (-899 8024);
PAINT GREEN (-899 8024);
FORCEPROP 1 LAST LOCATION Q78
J 0
(-899 8149);
DISPLAY 0.723404 (-899 8149);
PAINT GREEN (-899 8149);
FORCEPROP 0 LASTPIN (-1000 8375) $PN 6
R 1
J 0
(-1010 8385);
DISPLAY 0.808511 (-1010 8385);
FORCEPROP 0 LASTPIN (-1250 8125) $PN 2
J 2
(-1260 8135);
DISPLAY 0.808511 (-1260 8135);
FORCEPROP 0 LASTPIN (-1000 7975) $PN 1
R 1
J 2
(-1010 7965);
DISPLAY 0.808511 (-1010 7965);
FORCEPROP 1 LAST PATH I34
J 0
(-1050 8175);
DISPLAY 0.723404 (-1050 8175);
PAINT GREEN (-1050 8175);
DISPLAY INVISIBLE (-1050 8175);
FORCEPROP 1 LAST NEEDS_NO_SIZE TRUE
J 0
(-1050 8174);
DISPLAY 0.468085 (-1050 8174);
PAINT GREEN (-1050 8174);
DISPLAY INVISIBLE (-1050 8174);
FORCEPROP 1 LAST CDS_LMAN_SYM_OUTLINE -150,150,150,-150
J 0
(-1050 8175);
DISPLAY 0.468085 (-1050 8175);
PAINT GREEN (-1050 8175);
DISPLAY INVISIBLE (-1050 8175);
FORCEPROP 2 LAST CDS_LIB pure_quanta
J 0
(-1050 8175);
DISPLAY INVISIBLE (-1050 8175);
FORCEPROP 0 LAST $SEC 1
J 0
(-875 8300);
DISPLAY INVISIBLE (-875 8300);
FORCEPROP 0 LAST CDS_SEC 1
J 0
(-875 8300);
DISPLAY INVISIBLE (-875 8300);
FORCEADD Q_LED..1
R 2
(25 8450);
FORCEPROP 1 LAST PART_NUMBER BEBL0172Z00
J 0
(-75 8225);
DISPLAY 0.574468 (-75 8225);
PAINT GREEN (-75 8225);
DISPLAY INVISIBLE (-75 8225);
FORCEPROP 2 LAST COLOR LED_BLUE
J 0
(-75 8325);
DISPLAY 0.638298 (-75 8325);
FORCEPROP 1 LAST MATERIAL IC
J 0
(50 8275);
DISPLAY 0.723404 (50 8275);
PAINT GREEN (50 8275);
FORCEPROP 2 LAST MANUF_PN LTST-C281TBKT-5A
J 0
(-75 8175);
DISPLAY 0.638298 (-75 8175);
FORCEPROP 0 LAST PACK_TYPE SMLF
J 0
(-75 8275);
DISPLAY 0.638298 (-75 8275);
FORCEPROP 1 LAST LOCATION D95
J 0
(-75 8375);
DISPLAY 0.723404 (-75 8375);
PAINT GREEN (-75 8375);
FORCEPROP 0 LASTPIN (175 8450) $PN A
J 0
(185 8460);
DISPLAY 0.808511 (185 8460);
FORCEPROP 0 LASTPIN (-125 8450) $PN C
J 2
(-135 8460);
DISPLAY 0.808511 (-135 8460);
FORCEPROP 1 LAST PATH I35
J 2
(-100 8530);
DISPLAY 0.723404 (-100 8530);
PAINT GREEN (-100 8530);
DISPLAY INVISIBLE (-100 8530);
FORCEPROP 1 LAST NEEDS_NO_SIZE TRUE
J 2
(47 8472);
DISPLAY 0.468085 (47 8472);
PAINT GREEN (47 8472);
DISPLAY INVISIBLE (47 8472);
FORCEPROP 2 LAST CDS_LIB pure_quanta
J 0
(25 8450);
DISPLAY INVISIBLE (25 8450);
FORCEPROP 0 LAST $SEC 1
J 0
(-75 8425);
DISPLAY INVISIBLE (-75 8425);
FORCEPROP 0 LAST CDS_SEC 1
J 0
(-75 8425);
DISPLAY INVISIBLE (-75 8425);
FORCEADD Q_RES..1
(1325 7125);
FORCEPROP 1 LAST PART_NUMBER CS11302FB03
J 0
(1100 7225);
DISPLAY 0.638298 (1100 7225);
DISPLAY INVISIBLE (1100 7225);
FORCEPROP 1 LAST PACK_TYPE 0402LF
J 0
(1625 7125);
DISPLAY 0.638298 (1625 7125);
FORCEPROP 1 LAST WATTAGE 1/16W
J 2
(1475 7075);
DISPLAY 0.638298 (1475 7075);
FORCEPROP 1 LAST MATERIAL CHIP
J 0
(1175 7075);
DISPLAY 0.638298 (1175 7075);
FORCEPROP 1 LAST TOLERANCE 1%
J 0
(1550 7125);
DISPLAY 0.638298 (1550 7125);
FORCEPROP 1 LAST VALUE 130
J 2
(1525 7125);
DISPLAY 0.638298 (1525 7125);
FORCEPROP 1 LAST $LOCATION R3075
J 0
(1275 7175);
DISPLAY 0.978723 (1275 7175);
FORCEPROP 1 LASTPIN (1225 7125) $PN 1
J 0
(1237 7137);
DISPLAY 0.787234 (1237 7137);
PAINT MONO (1237 7137);
FORCEPROP 1 LASTPIN (1425 7125) $PN 2
J 0
(1387 7137);
DISPLAY 0.787234 (1387 7137);
PAINT MONO (1387 7137);
FORCEPROP 1 LAST PATH I37
J 0
(1275 7275);
DISPLAY 0.978723 (1275 7275);
PAINT WHITE (1275 7275);
DISPLAY INVISIBLE (1275 7275);
FORCEPROP 2 LAST CDS_LIB pure_quanta
J 0
(1325 7125);
DISPLAY INVISIBLE (1325 7125);
FORCEPROP 0 LAST CDS_LOCATION R3075
J 0
(1275 7225);
DISPLAY 1.021277 (1275 7225);
DISPLAY INVISIBLE (1275 7225);
FORCEPROP 0 LAST $SEC 1
J 0
(1275 7225);
DISPLAY 0.680851 (1275 7225);
PAINT MONO (1275 7225);
DISPLAY INVISIBLE (1275 7225);
FORCEPROP 0 LAST CDS_SEC 1
J 0
(1275 7225);
DISPLAY 1.021277 (1275 7225);
DISPLAY INVISIBLE (1275 7225);
FORCEADD UNIVERSAL_POWER..1
(1975 7275);
FORCEPROP 3 LASTPIN (1975 7225) SIG_NAME P3V3_AUX\g
J 0
(1985 7235);
DISPLAY 0.659574 (1985 7235);
PAINT MONO (1985 7235);
DISPLAY INVISIBLE (1985 7235);
FORCEPROP 1 LAST HDL_POWER P3V3_AUX
J 1
(1975 7325);
DISPLAY 0.723404 (1975 7325);
PAINT GREEN (1975 7325);
FORCEPROP 1 LAST PATH I39
J 0
(2025 7300);
DISPLAY 0.872340 (2025 7300);
PAINT AQUA (2025 7300);
DISPLAY INVISIBLE (2025 7300);
FORCEPROP 2 LAST CDS_LIB logical_power
J 0
(1975 7275);
DISPLAY INVISIBLE (1975 7275);
FORCEADD UNIVERSAL_GND..1
(-5775 3950);
FORCEPROP 3 LASTPIN (-5775 4000) SIG_NAME GND\g
J 0
(-5765 4010);
DISPLAY 0.659574 (-5765 4010);
PAINT MONO (-5765 4010);
DISPLAY INVISIBLE (-5765 4010);
FORCEPROP 1 LAST PATH I4
J 0
(-5700 3950);
DISPLAY 0.872340 (-5700 3950);
PAINT AQUA (-5700 3950);
DISPLAY INVISIBLE (-5700 3950);
FORCEPROP 1 LAST HDL_POWER GND
J 1
(-5750 3875);
DISPLAY 0.872340 (-5750 3875);
PAINT GREEN (-5750 3875);
DISPLAY INVISIBLE (-5750 3875);
FORCEPROP 2 LAST CDS_LIB logical_power
J 0
(-5775 3950);
DISPLAY INVISIBLE (-5775 3950);
FORCEADD UNIVERSAL_POWER..1
(1950 8625);
FORCEPROP 3 LASTPIN (1950 8575) SIG_NAME P3V3_AUX\g
J 0
(1960 8585);
DISPLAY 0.659574 (1960 8585);
PAINT MONO (1960 8585);
DISPLAY INVISIBLE (1960 8585);
FORCEPROP 1 LAST HDL_POWER P3V3_AUX
J 1
(1950 8675);
DISPLAY 0.723404 (1950 8675);
PAINT GREEN (1950 8675);
FORCEPROP 1 LAST PATH I40
J 0
(2000 8650);
DISPLAY 0.872340 (2000 8650);
PAINT AQUA (2000 8650);
DISPLAY INVISIBLE (2000 8650);
FORCEPROP 2 LAST CDS_LIB logical_power
J 0
(1950 8625);
DISPLAY INVISIBLE (1950 8625);
FORCEADD Q_RES..1
(1350 8450);
FORCEPROP 1 LAST PART_NUMBER CS11302FB03
J 0
(1125 8550);
DISPLAY 0.638298 (1125 8550);
DISPLAY INVISIBLE (1125 8550);
FORCEPROP 1 LAST VALUE 130
J 2
(1550 8450);
DISPLAY 0.638298 (1550 8450);
FORCEPROP 1 LAST TOLERANCE 1%
J 0
(1575 8450);
DISPLAY 0.638298 (1575 8450);
FORCEPROP 1 LAST MATERIAL CHIP
J 0
(1200 8400);
DISPLAY 0.638298 (1200 8400);
FORCEPROP 1 LAST WATTAGE 1/16W
J 2
(1500 8400);
DISPLAY 0.638298 (1500 8400);
FORCEPROP 1 LAST PACK_TYPE 0402LF
J 0
(1650 8450);
DISPLAY 0.638298 (1650 8450);
FORCEPROP 1 LAST $LOCATION R3078
J 0
(1300 8500);
DISPLAY 0.978723 (1300 8500);
FORCEPROP 1 LASTPIN (1250 8450) $PN 1
J 0
(1262 8462);
DISPLAY 0.787234 (1262 8462);
PAINT MONO (1262 8462);
FORCEPROP 1 LASTPIN (1450 8450) $PN 2
J 0
(1412 8462);
DISPLAY 0.787234 (1412 8462);
PAINT MONO (1412 8462);
FORCEPROP 1 LAST PATH I41
J 0
(1300 8600);
DISPLAY 0.978723 (1300 8600);
PAINT WHITE (1300 8600);
DISPLAY INVISIBLE (1300 8600);
FORCEPROP 2 LAST CDS_LIB pure_quanta
J 0
(1350 8450);
DISPLAY INVISIBLE (1350 8450);
FORCEPROP 0 LAST CDS_LOCATION R3078
J 0
(1300 8550);
DISPLAY 1.021277 (1300 8550);
DISPLAY INVISIBLE (1300 8550);
FORCEPROP 0 LAST $SEC 1
J 0
(1300 8550);
DISPLAY 0.680851 (1300 8550);
PAINT MONO (1300 8550);
DISPLAY INVISIBLE (1300 8550);
FORCEPROP 0 LAST CDS_SEC 1
J 0
(1300 8550);
DISPLAY 1.021277 (1300 8550);
DISPLAY INVISIBLE (1300 8550);
FORCEADD Q_LED..1
R 2
(-4750 7125);
FORCEPROP 1 LAST PART_NUMBER BEBL0172Z00
J 0
(-4850 6900);
DISPLAY 0.574468 (-4850 6900);
PAINT GREEN (-4850 6900);
DISPLAY INVISIBLE (-4850 6900);
FORCEPROP 2 LAST MANUF_PN LTST-C281TBKT-5A
J 0
(-4850 6850);
DISPLAY 0.638298 (-4850 6850);
FORCEPROP 0 LAST PACK_TYPE SMLF
J 0
(-4850 6950);
DISPLAY 0.638298 (-4850 6950);
FORCEPROP 1 LAST MATERIAL IC
J 0
(-4725 6950);
DISPLAY 0.723404 (-4725 6950);
PAINT GREEN (-4725 6950);
FORCEPROP 2 LAST COLOR LED_BLUE
J 0
(-4850 7000);
DISPLAY 0.638298 (-4850 7000);
FORCEPROP 1 LAST LOCATION D92
J 0
(-4850 7050);
DISPLAY 0.723404 (-4850 7050);
PAINT GREEN (-4850 7050);
FORCEPROP 0 LASTPIN (-4600 7125) $PN A
J 0
(-4590 7135);
DISPLAY 0.808511 (-4590 7135);
FORCEPROP 0 LASTPIN (-4900 7125) $PN C
J 2
(-4910 7135);
DISPLAY 0.808511 (-4910 7135);
FORCEPROP 1 LAST PATH I42
J 2
(-4875 7205);
DISPLAY 0.723404 (-4875 7205);
PAINT GREEN (-4875 7205);
DISPLAY INVISIBLE (-4875 7205);
FORCEPROP 2 LAST CDS_LIB pure_quanta
J 0
(-4750 7125);
DISPLAY INVISIBLE (-4750 7125);
FORCEPROP 1 LAST NEEDS_NO_SIZE TRUE
J 2
(-4728 7147);
DISPLAY 0.468085 (-4728 7147);
PAINT GREEN (-4728 7147);
DISPLAY INVISIBLE (-4728 7147);
FORCEPROP 0 LAST $SEC 1
J 0
(-4850 7100);
DISPLAY INVISIBLE (-4850 7100);
FORCEPROP 0 LAST CDS_SEC 1
J 0
(-4850 7100);
DISPLAY INVISIBLE (-4850 7100);
FORCEADD UNIVERSAL_GND..1
(-1725 5500);
FORCEPROP 3 LASTPIN (-1725 5550) SIG_NAME GND\g
J 0
(-1715 5560);
DISPLAY 0.659574 (-1715 5560);
PAINT MONO (-1715 5560);
DISPLAY INVISIBLE (-1715 5560);
FORCEPROP 2 LAST CDS_LIB logical_power
J 0
(-1725 5500);
DISPLAY INVISIBLE (-1725 5500);
FORCEPROP 1 LAST HDL_POWER GND
J 1
(-1700 5425);
DISPLAY 0.872340 (-1700 5425);
PAINT GREEN (-1700 5425);
DISPLAY INVISIBLE (-1700 5425);
FORCEPROP 1 LAST PATH I49
J 0
(-1650 5500);
DISPLAY 0.872340 (-1650 5500);
PAINT AQUA (-1650 5500);
DISPLAY INVISIBLE (-1650 5500);
FORCEADD UNIVERSAL_GND..1
(-5775 5275);
FORCEPROP 3 LASTPIN (-5775 5325) SIG_NAME GND\g
J 0
(-5765 5335);
DISPLAY 0.659574 (-5765 5335);
PAINT MONO (-5765 5335);
DISPLAY INVISIBLE (-5765 5335);
FORCEPROP 1 LAST PATH I5
J 0
(-5700 5275);
DISPLAY 0.872340 (-5700 5275);
PAINT AQUA (-5700 5275);
DISPLAY INVISIBLE (-5700 5275);
FORCEPROP 1 LAST HDL_POWER GND
J 1
(-5750 5200);
DISPLAY 0.872340 (-5750 5200);
PAINT GREEN (-5750 5200);
DISPLAY INVISIBLE (-5750 5200);
FORCEPROP 2 LAST CDS_LIB logical_power
J 0
(-5775 5275);
DISPLAY INVISIBLE (-5775 5275);
FORCEADD UNIVERSAL_POWER..1
(375 6000);
FORCEPROP 3 LASTPIN (375 5950) SIG_NAME P5V_AUX\g
J 0
(385 5960);
DISPLAY 0.659574 (385 5960);
PAINT MONO (385 5960);
DISPLAY INVISIBLE (385 5960);
FORCEPROP 1 LAST HDL_POWER P5V_AUX
J 1
(375 6050);
DISPLAY 0.723404 (375 6050);
PAINT GREEN (375 6050);
FORCEPROP 2 LAST CDS_LIB logical_power
J 0
(375 6000);
DISPLAY INVISIBLE (375 6000);
FORCEPROP 1 LAST PATH I51
J 0
(425 6025);
DISPLAY 0.872340 (425 6025);
PAINT AQUA (425 6025);
DISPLAY INVISIBLE (425 6025);
FORCEADD Q_LED..1
R 2
(-1125 5750);
FORCEPROP 1 LAST PART_NUMBER BEBL0172Z00
J 0
(-1225 5525);
DISPLAY 0.574468 (-1225 5525);
PAINT GREEN (-1225 5525);
DISPLAY INVISIBLE (-1225 5525);
FORCEPROP 2 LAST COLOR LED_BLUE
J 0
(-1225 5625);
DISPLAY 0.638298 (-1225 5625);
FORCEPROP 2 LAST MANUF_PN LTST-C281TBKT-5A
J 0
(-1225 5475);
DISPLAY 0.638298 (-1225 5475);
FORCEPROP 0 LAST PACK_TYPE SMLF
J 0
(-1225 5575);
DISPLAY 0.638298 (-1225 5575);
FORCEPROP 1 LAST MATERIAL IC
J 0
(-1100 5575);
DISPLAY 0.723404 (-1100 5575);
PAINT GREEN (-1100 5575);
FORCEPROP 1 LAST LOCATION D97
J 0
(-1225 5675);
DISPLAY 0.723404 (-1225 5675);
PAINT GREEN (-1225 5675);
FORCEPROP 0 LASTPIN (-975 5750) $PN A
J 0
(-965 5760);
DISPLAY 0.808511 (-965 5760);
FORCEPROP 0 LASTPIN (-1275 5750) $PN C
J 2
(-1285 5760);
DISPLAY 0.808511 (-1285 5760);
FORCEPROP 2 LAST CDS_LIB pure_quanta
J 0
(-1125 5750);
DISPLAY INVISIBLE (-1125 5750);
FORCEPROP 1 LAST NEEDS_NO_SIZE TRUE
J 2
(-1103 5772);
DISPLAY 0.468085 (-1103 5772);
PAINT GREEN (-1103 5772);
DISPLAY INVISIBLE (-1103 5772);
FORCEPROP 1 LAST PATH I52
J 2
(-1250 5830);
DISPLAY 0.723404 (-1250 5830);
PAINT GREEN (-1250 5830);
DISPLAY INVISIBLE (-1250 5830);
FORCEPROP 0 LAST $SEC 1
J 0
(-1225 5725);
DISPLAY INVISIBLE (-1225 5725);
FORCEPROP 0 LAST CDS_SEC 1
J 0
(-1225 5725);
DISPLAY INVISIBLE (-1225 5725);
FORCEADD Q_LED..1
R 2
(-1100 4625);
FORCEPROP 1 LAST PART_NUMBER BEBL0172Z00
J 0
(-1200 4400);
DISPLAY 0.574468 (-1200 4400);
PAINT GREEN (-1200 4400);
DISPLAY INVISIBLE (-1200 4400);
FORCEPROP 2 LAST COLOR LED_BLUE
J 0
(-1200 4500);
DISPLAY 0.638298 (-1200 4500);
FORCEPROP 0 LAST PACK_TYPE SMLF
J 0
(-1200 4450);
DISPLAY 0.638298 (-1200 4450);
FORCEPROP 1 LAST MATERIAL IC
J 0
(-1075 4450);
DISPLAY 0.723404 (-1075 4450);
PAINT GREEN (-1075 4450);
FORCEPROP 2 LAST MANUF_PN LTST-C281TBKT-5A
J 0
(-1200 4350);
DISPLAY 0.638298 (-1200 4350);
FORCEPROP 1 LAST LOCATION D98
J 0
(-1200 4550);
DISPLAY 0.723404 (-1200 4550);
PAINT GREEN (-1200 4550);
FORCEPROP 0 LASTPIN (-950 4625) $PN A
J 0
(-940 4635);
DISPLAY 0.808511 (-940 4635);
FORCEPROP 0 LASTPIN (-1250 4625) $PN C
J 2
(-1260 4635);
DISPLAY 0.808511 (-1260 4635);
FORCEPROP 1 LAST NEEDS_NO_SIZE TRUE
J 2
(-1078 4647);
DISPLAY 0.468085 (-1078 4647);
PAINT GREEN (-1078 4647);
DISPLAY INVISIBLE (-1078 4647);
FORCEPROP 2 LAST CDS_LIB pure_quanta
J 0
(-1100 4625);
DISPLAY INVISIBLE (-1100 4625);
FORCEPROP 1 LAST PATH I53
J 2
(-1225 4705);
DISPLAY 0.723404 (-1225 4705);
PAINT GREEN (-1225 4705);
DISPLAY INVISIBLE (-1225 4705);
FORCEPROP 0 LAST $SEC 1
J 0
(-1200 4600);
DISPLAY INVISIBLE (-1200 4600);
FORCEPROP 0 LAST CDS_SEC 1
J 0
(-1200 4600);
DISPLAY INVISIBLE (-1200 4600);
FORCEADD UNIVERSAL_POWER..1
(400 4875);
FORCEPROP 3 LASTPIN (400 4825) SIG_NAME P5V\g
J 0
(410 4835);
DISPLAY 0.659574 (410 4835);
PAINT MONO (410 4835);
DISPLAY INVISIBLE (410 4835);
FORCEPROP 1 LAST HDL_POWER P5V
J 1
(400 4925);
DISPLAY 0.723404 (400 4925);
PAINT GREEN (400 4925);
FORCEPROP 2 LAST CDS_LIB logical_power
J 0
(400 4875);
DISPLAY INVISIBLE (400 4875);
FORCEPROP 1 LAST PATH I54
J 0
(450 4900);
DISPLAY 0.872340 (450 4900);
PAINT AQUA (450 4900);
DISPLAY INVISIBLE (450 4900);
FORCEADD UNIVERSAL_GND..1
(-1700 4375);
FORCEPROP 3 LASTPIN (-1700 4425) SIG_NAME GND\g
J 0
(-1690 4435);
DISPLAY 0.659574 (-1690 4435);
PAINT MONO (-1690 4435);
DISPLAY INVISIBLE (-1690 4435);
FORCEPROP 1 LAST HDL_POWER GND
J 1
(-1675 4300);
DISPLAY 0.872340 (-1675 4300);
PAINT GREEN (-1675 4300);
DISPLAY INVISIBLE (-1675 4300);
FORCEPROP 2 LAST CDS_LIB logical_power
J 0
(-1700 4375);
DISPLAY INVISIBLE (-1700 4375);
FORCEPROP 1 LAST PATH I56
J 0
(-1625 4375);
DISPLAY 0.872340 (-1625 4375);
PAINT AQUA (-1625 4375);
DISPLAY INVISIBLE (-1625 4375);
FORCEADD UNIVERSAL_GND..1
(-1775 3150);
FORCEPROP 3 LASTPIN (-1775 3200) SIG_NAME GND\g
J 0
(-1765 3210);
DISPLAY 0.659574 (-1765 3210);
PAINT MONO (-1765 3210);
DISPLAY INVISIBLE (-1765 3210);
FORCEPROP 2 LAST CDS_LIB logical_power
J 0
(-1775 3150);
DISPLAY INVISIBLE (-1775 3150);
FORCEPROP 1 LAST HDL_POWER GND
J 1
(-1750 3075);
DISPLAY 0.872340 (-1750 3075);
PAINT GREEN (-1750 3075);
DISPLAY INVISIBLE (-1750 3075);
FORCEPROP 1 LAST PATH I57
J 0
(-1700 3150);
DISPLAY 0.872340 (-1700 3150);
PAINT AQUA (-1700 3150);
DISPLAY INVISIBLE (-1700 3150);
FORCEADD UNIVERSAL_POWER..1
(450 3625);
FORCEPROP 3 LASTPIN (450 3575) SIG_NAME P3V3\g
J 0
(460 3585);
DISPLAY 0.659574 (460 3585);
PAINT MONO (460 3585);
DISPLAY INVISIBLE (460 3585);
FORCEPROP 1 LAST HDL_POWER P3V3
J 1
(450 3675);
DISPLAY 0.723404 (450 3675);
PAINT GREEN (450 3675);
FORCEPROP 2 LAST CDS_LIB logical_power
J 0
(450 3625);
DISPLAY INVISIBLE (450 3625);
FORCEPROP 1 LAST PATH I59
J 0
(500 3650);
DISPLAY 0.872340 (500 3650);
PAINT AQUA (500 3650);
DISPLAY INVISIBLE (500 3650);
FORCEADD MOSFET_NCH_DUAL..1
(-5825 5625);
FORCEPROP 1 LAST PART_NUMBER BAM138K0003
J 0
(-5674 5539);
DISPLAY 0.723404 (-5674 5539);
PAINT GREEN (-5674 5539);
DISPLAY INVISIBLE (-5674 5539);
FORCEPROP 2 LAST PART_TYPE SMLF
J 0
(-5650 5700);
DISPLAY 1.021277 (-5650 5700);
FORCEPROP 2 LAST VALUE PJT138K
J 0
(-5650 5650);
DISPLAY 1.021277 (-5650 5650);
FORCEPROP 1 LAST MATERIAL IC
J 0
(-5674 5474);
DISPLAY 0.723404 (-5674 5474);
PAINT GREEN (-5674 5474);
FORCEPROP 1 LAST LOCATION Q77
J 0
(-5674 5599);
DISPLAY 0.723404 (-5674 5599);
PAINT GREEN (-5674 5599);
FORCEPROP 0 LASTPIN (-5775 5825) $PN 6
R 1
J 0
(-5785 5835);
DISPLAY 0.808511 (-5785 5835);
FORCEPROP 0 LASTPIN (-6025 5575) $PN 2
J 2
(-6035 5585);
DISPLAY 0.808511 (-6035 5585);
FORCEPROP 0 LASTPIN (-5775 5425) $PN 1
R 1
J 2
(-5785 5415);
DISPLAY 0.808511 (-5785 5415);
FORCEPROP 1 LAST PATH I6
J 0
(-5825 5625);
DISPLAY 0.723404 (-5825 5625);
PAINT GREEN (-5825 5625);
DISPLAY INVISIBLE (-5825 5625);
FORCEPROP 1 LAST NEEDS_NO_SIZE TRUE
J 0
(-5825 5624);
DISPLAY 0.468085 (-5825 5624);
PAINT GREEN (-5825 5624);
DISPLAY INVISIBLE (-5825 5624);
FORCEPROP 1 LAST CDS_LMAN_SYM_OUTLINE -150,150,150,-150
J 0
(-5825 5625);
DISPLAY 0.468085 (-5825 5625);
PAINT GREEN (-5825 5625);
DISPLAY INVISIBLE (-5825 5625);
FORCEPROP 2 LAST CDS_LIB pure_quanta
J 0
(-5825 5625);
DISPLAY INVISIBLE (-5825 5625);
FORCEPROP 0 LAST $SEC 1
J 0
(-5650 5750);
DISPLAY INVISIBLE (-5650 5750);
FORCEPROP 0 LAST CDS_SEC 1
J 0
(-5650 5750);
DISPLAY INVISIBLE (-5650 5750);
FORCEADD Q_LED..1
R 2
(-1175 3400);
FORCEPROP 1 LAST PART_NUMBER BEBL0172Z00
J 0
(-1275 3175);
DISPLAY 0.574468 (-1275 3175);
PAINT GREEN (-1275 3175);
DISPLAY INVISIBLE (-1275 3175);
FORCEPROP 2 LAST COLOR LED_BLUE
J 0
(-1275 3275);
DISPLAY 0.638298 (-1275 3275);
FORCEPROP 0 LAST PACK_TYPE SMLF
J 0
(-1275 3225);
DISPLAY 0.638298 (-1275 3225);
FORCEPROP 1 LAST MATERIAL IC
J 0
(-1150 3225);
DISPLAY 0.723404 (-1150 3225);
PAINT GREEN (-1150 3225);
FORCEPROP 2 LAST MANUF_PN LTST-C281TBKT-5A
J 0
(-1275 3125);
DISPLAY 0.638298 (-1275 3125);
FORCEPROP 1 LAST LOCATION D99
J 0
(-1275 3325);
DISPLAY 0.723404 (-1275 3325);
PAINT GREEN (-1275 3325);
FORCEPROP 0 LASTPIN (-1025 3400) $PN A
J 0
(-1015 3410);
DISPLAY 0.808511 (-1015 3410);
FORCEPROP 0 LASTPIN (-1325 3400) $PN C
J 2
(-1335 3410);
DISPLAY 0.808511 (-1335 3410);
FORCEPROP 2 LAST CDS_LIB pure_quanta
J 0
(-1175 3400);
DISPLAY INVISIBLE (-1175 3400);
FORCEPROP 1 LAST NEEDS_NO_SIZE TRUE
J 2
(-1153 3422);
DISPLAY 0.468085 (-1153 3422);
PAINT GREEN (-1153 3422);
DISPLAY INVISIBLE (-1153 3422);
FORCEPROP 1 LAST PATH I60
J 2
(-1300 3480);
DISPLAY 0.723404 (-1300 3480);
PAINT GREEN (-1300 3480);
DISPLAY INVISIBLE (-1300 3480);
FORCEPROP 0 LAST $SEC 1
J 0
(-1275 3375);
DISPLAY INVISIBLE (-1275 3375);
FORCEPROP 0 LAST CDS_SEC 1
J 0
(-1275 3375);
DISPLAY INVISIBLE (-1275 3375);
FORCEADD Q_RES..1
(0 4625);
FORCEPROP 1 LAST PART_NUMBER CS14702FB04
J 0
(-125 4550);
DISPLAY 0.638298 (-125 4550);
DISPLAY INVISIBLE (-125 4550);
FORCEPROP 1 LAST MATERIAL CHIP
J 0
(-125 4500);
DISPLAY 0.638298 (-125 4500);
FORCEPROP 1 LAST WATTAGE 1/16W
J 2
(150 4500);
DISPLAY 0.638298 (150 4500);
FORCEPROP 1 LAST VALUE 470
J 2
(-50 4575);
DISPLAY 0.638298 (-50 4575);
FORCEPROP 1 LAST TOLERANCE 1%
J 0
(-25 4575);
DISPLAY 0.638298 (-25 4575);
FORCEPROP 1 LAST PACK_TYPE 0402LF
J 0
(50 4575);
DISPLAY 0.638298 (50 4575);
FORCEPROP 1 LAST $LOCATION R3102
J 0
(-125 4625);
DISPLAY 0.638298 (-125 4625);
FORCEPROP 1 LASTPIN (-100 4625) $PN 1
J 0
(-88 4637);
DISPLAY 0.787234 (-88 4637);
PAINT MONO (-88 4637);
FORCEPROP 1 LASTPIN (100 4625) $PN 2
J 0
(62 4637);
DISPLAY 0.787234 (62 4637);
PAINT MONO (62 4637);
FORCEPROP 1 LAST PATH I61
J 0
(-50 4775);
DISPLAY 0.978723 (-50 4775);
PAINT WHITE (-50 4775);
DISPLAY INVISIBLE (-50 4775);
FORCEPROP 2 LAST CDS_LIB pure_quanta
J 0
(0 4625);
DISPLAY INVISIBLE (0 4625);
FORCEPROP 0 LAST CDS_LOCATION R3102
J 0
(-125 4675);
DISPLAY 1.021277 (-125 4675);
DISPLAY INVISIBLE (-125 4675);
FORCEPROP 0 LAST $SEC 1
J 0
(-125 4675);
DISPLAY 0.680851 (-125 4675);
PAINT MONO (-125 4675);
DISPLAY INVISIBLE (-125 4675);
FORCEPROP 0 LAST CDS_SEC 1
J 0
(-125 4675);
DISPLAY 1.021277 (-125 4675);
DISPLAY INVISIBLE (-125 4675);
FORCEADD Q_RES..1
(-25 5750);
FORCEPROP 1 LAST PART_NUMBER CS14702FB04
J 0
(-150 5675);
DISPLAY 0.638298 (-150 5675);
DISPLAY INVISIBLE (-150 5675);
FORCEPROP 1 LAST MATERIAL CHIP
J 0
(-150 5625);
DISPLAY 0.638298 (-150 5625);
FORCEPROP 1 LAST WATTAGE 1/16W
J 2
(125 5625);
DISPLAY 0.638298 (125 5625);
FORCEPROP 1 LAST VALUE 470
J 2
(-75 5700);
DISPLAY 0.638298 (-75 5700);
FORCEPROP 1 LAST TOLERANCE 1%
J 0
(-50 5700);
DISPLAY 0.638298 (-50 5700);
FORCEPROP 1 LAST PACK_TYPE 0402LF
J 0
(25 5700);
DISPLAY 0.638298 (25 5700);
FORCEPROP 1 LAST $LOCATION R3101
J 0
(-75 5800);
DISPLAY 0.978723 (-75 5800);
FORCEPROP 1 LASTPIN (-125 5750) $PN 1
J 0
(-113 5762);
DISPLAY 0.787234 (-113 5762);
PAINT MONO (-113 5762);
FORCEPROP 1 LASTPIN (75 5750) $PN 2
J 0
(37 5762);
DISPLAY 0.787234 (37 5762);
PAINT MONO (37 5762);
FORCEPROP 2 LAST CDS_LIB pure_quanta
J 0
(-25 5750);
DISPLAY INVISIBLE (-25 5750);
FORCEPROP 1 LAST PATH I62
J 0
(-75 5900);
DISPLAY 0.978723 (-75 5900);
PAINT WHITE (-75 5900);
DISPLAY INVISIBLE (-75 5900);
FORCEPROP 0 LAST CDS_LOCATION R3101
J 0
(-75 5850);
DISPLAY 1.021277 (-75 5850);
DISPLAY INVISIBLE (-75 5850);
FORCEPROP 0 LAST $SEC 1
J 0
(-75 5850);
DISPLAY 0.680851 (-75 5850);
PAINT MONO (-75 5850);
DISPLAY INVISIBLE (-75 5850);
FORCEPROP 0 LAST CDS_SEC 1
J 0
(-75 5850);
DISPLAY 1.021277 (-75 5850);
DISPLAY INVISIBLE (-75 5850);
FORCEADD Q_RES..1
(-75 3400);
FORCEPROP 1 LAST PART_NUMBER CS11302FB03
J 0
(-300 3500);
DISPLAY 0.638298 (-300 3500);
DISPLAY INVISIBLE (-300 3500);
FORCEPROP 1 LAST WATTAGE 1/16W
J 2
(75 3350);
DISPLAY 0.638298 (75 3350);
FORCEPROP 1 LAST VALUE 130
J 2
(125 3400);
DISPLAY 0.638298 (125 3400);
FORCEPROP 1 LAST TOLERANCE 1%
J 0
(150 3400);
DISPLAY 0.638298 (150 3400);
FORCEPROP 1 LAST MATERIAL CHIP
J 0
(-225 3350);
DISPLAY 0.638298 (-225 3350);
FORCEPROP 1 LAST PACK_TYPE 0402LF
J 0
(225 3400);
DISPLAY 0.638298 (225 3400);
FORCEPROP 1 LAST LOCATION R3100
J 0
(-125 3450);
DISPLAY 0.978723 (-125 3450);
FORCEPROP 1 LASTPIN (-175 3400) $PN 1
J 0
(-163 3412);
DISPLAY 0.787234 (-163 3412);
PAINT MONO (-163 3412);
FORCEPROP 1 LASTPIN (25 3400) $PN 2
J 0
(-13 3412);
DISPLAY 0.787234 (-13 3412);
PAINT MONO (-13 3412);
FORCEPROP 1 LAST PATH I64
J 0
(-125 3550);
DISPLAY 0.978723 (-125 3550);
PAINT WHITE (-125 3550);
DISPLAY INVISIBLE (-125 3550);
FORCEPROP 2 LAST CDS_LIB pure_quanta
J 0
(-75 3400);
DISPLAY INVISIBLE (-75 3400);
FORCEPROP 0 LAST $SEC 1
J 0
(-125 3500);
DISPLAY 0.680851 (-125 3500);
PAINT MONO (-125 3500);
DISPLAY INVISIBLE (-125 3500);
FORCEPROP 0 LAST CDS_SEC 1
J 0
(-125 3500);
DISPLAY 1.021277 (-125 3500);
DISPLAY INVISIBLE (-125 3500);
FORCEADD OFFPAGE..1
(-6925 6800);
PAINT AQUA (-6925 6800);
FORCEPROP 2 LAST $XR1 214 
J 0
(-7177 6764);
DISPLAY 0.638298 (-7177 6764);
PAINT MONO (-7177 6764);
FORCEPROP 2 LAST $XR0 262 
J 0
(-7177 6800);
DISPLAY 0.638298 (-7177 6800);
PAINT MONO (-7177 6800);
FORCEPROP 2 LAST PATH I7
J 0
(-7175 6850);
DISPLAY 1.021277 (-7175 6850);
DISPLAY INVISIBLE (-7175 6850);
FORCEPROP 1 LAST COMMENT_BODY TRUE
J 0
(-6800 6700);
DISPLAY 0.872340 (-6800 6700);
PAINT GREEN (-6800 6700);
DISPLAY INVISIBLE (-6800 6700);
FORCEPROP 1 LAST OFFPAGE TRUE
J 0
(-6600 6675);
DISPLAY 0.872340 (-6600 6675);
PAINT AQUA (-6600 6675);
DISPLAY INVISIBLE (-6600 6675);
FORCEPROP 2 LAST CDS_LIB standard
J 0
(-6925 6800);
DISPLAY INVISIBLE (-6925 6800);
FORCEADD MOSFET_NCH_DUAL..2
(-5825 6850);
FORCEPROP 1 LAST PART_NUMBER BAM138K0003
J 0
(-5674 6756);
DISPLAY 0.723404 (-5674 6756);
PAINT BLUE (-5674 6756);
DISPLAY INVISIBLE (-5674 6756);
FORCEPROP 1 LAST MATERIAL IC
J 0
(-5674 6701);
DISPLAY 0.723404 (-5674 6701);
PAINT SKYBLUE (-5674 6701);
FORCEPROP 2 LAST PART_TYPE SMLF
J 0
(-5650 6925);
DISPLAY 1.021277 (-5650 6925);
FORCEPROP 2 LAST VALUE PJT138K
J 0
(-5650 6875);
DISPLAY 0.723404 (-5650 6875);
PAINT SKYBLUE (-5650 6875);
FORCEPROP 1 LAST LOCATION Q76
J 0
(-5674 6826);
DISPLAY 0.723404 (-5674 6826);
PAINT AQUA (-5674 6826);
FORCEPROP 2 LASTPIN (-5775 7050) $PN 3
R 1
J 0
(-5785 7060);
DISPLAY 0.723404 (-5785 7060);
PAINT MONO (-5785 7060);
FORCEPROP 2 LASTPIN (-6025 6800) $PN 5
J 2
(-6035 6810);
DISPLAY 0.723404 (-6035 6810);
PAINT MONO (-6035 6810);
FORCEPROP 2 LASTPIN (-5775 6650) $PN 4
R 1
J 2
(-5785 6640);
DISPLAY 0.723404 (-5785 6640);
PAINT MONO (-5785 6640);
FORCEPROP 1 LAST PATH I8
J 0
(-5675 6700);
DISPLAY 0.723404 (-5675 6700);
PAINT GREEN (-5675 6700);
DISPLAY INVISIBLE (-5675 6700);
FORCEPROP 2 LAST SEC_TYPE 
J 0
(-5650 6975);
DISPLAY 1.021277 (-5650 6975);
DISPLAY INVISIBLE (-5650 6975);
FORCEPROP 2 LAST CDS_LIB pure_quanta
J 0
(-5825 6850);
DISPLAY INVISIBLE (-5825 6850);
FORCEPROP 1 LAST NEEDS_NO_SIZE TRUE
J 0
(-5675 6741);
DISPLAY 0.468085 (-5675 6741);
PAINT GREEN (-5675 6741);
DISPLAY INVISIBLE (-5675 6741);
FORCEPROP 1 LAST CDS_LMAN_SYM_OUTLINE -150,150,150,-150
J 0
(-5825 6850);
DISPLAY 0.468085 (-5825 6850);
PAINT GREEN (-5825 6850);
DISPLAY INVISIBLE (-5825 6850);
FORCEPROP 2 LAST SEC 2
J 0
(-5650 6975);
DISPLAY 0.680851 (-5650 6975);
PAINT MONO (-5650 6975);
DISPLAY INVISIBLE (-5650 6975);
FORCEADD UNIVERSAL_GND..1
(-5775 6500);
FORCEPROP 3 LASTPIN (-5775 6550) SIG_NAME GND\g
J 0
(-5765 6560);
DISPLAY 0.659574 (-5765 6560);
PAINT MONO (-5765 6560);
DISPLAY INVISIBLE (-5765 6560);
FORCEPROP 1 LAST PATH I9
J 0
(-5700 6500);
DISPLAY 0.872340 (-5700 6500);
PAINT AQUA (-5700 6500);
DISPLAY INVISIBLE (-5700 6500);
FORCEPROP 1 LAST HDL_POWER GND
J 1
(-5750 6425);
DISPLAY 0.872340 (-5750 6425);
PAINT GREEN (-5750 6425);
DISPLAY INVISIBLE (-5750 6425);
FORCEPROP 2 LAST CDS_LIB logical_power
J 0
(-5775 6500);
DISPLAY INVISIBLE (-5775 6500);
FORCEADD QUANTA_TITLE_BLOCK_C..1
(2150 2600);
FORCEPROP 0 LAST CDS_CON_LAST_MODIFIED Fri Aug 25 14:04:22 2023
J 0
(265 2615);
DISPLAY INVISIBLE (265 2615);
FORCEPROP 1 LAST CUSTOM_TXT_CDS <CON_LAST_MODIFIED>
J 0
(265 2615);
DISPLAY 0.978723 (265 2615);
FORCEPROP 2 LAST CUSTOM_TXT_CDS <XR_PAGE_TITLE>
J 0
(-5740 7850);
DISPLAY 0.638298 (-5740 7850);
PAINT PINK (-5740 7850);
DISPLAY INVISIBLE (-5740 7850);
FORCEPROP 1 LAST CUSTOM_TXT_CDS <NAME_2>
J 0
(-1025 2650);
FORCEPROP 1 LAST CUSTOM_TXT_CDS <NAME_1>
J 0
(-1025 2775);
FORCEPROP 1 LAST CUSTOM_TXT_CDS <Q_NUMBER>
J 0
(747 2703);
DISPLAY 1.212766 (747 2703);
FORCEPROP 1 LAST CUSTOM_TXT_CDS <Q_PROJ>
J 0
(-232 2702);
DISPLAY 1.212766 (-232 2702);
FORCEPROP 1 LAST CUSTOM_TXT_CDS <Q_REV>
J 0
(1966 2703);
DISPLAY 1.212766 (1966 2703);
FORCEPROP 1 LAST CUSTOM_TXT_CDS <CON_PAGE_NUM> OF <CON_TOTAL_PAGES>
J 0
(1704 2618);
DISPLAY 0.978723 (1704 2618);
FORCEPROP 1 LAST Q_TITLE POWER GOOD LED'S 1/5
J 0
(-7216 2626);
DISPLAY 2.446809 (-7216 2626);
PAINT GREEN (-7216 2626);
FORCEPROP 1 LAST Q_DEPT 
J 1
(-1613 2649);
DISPLAY 1.957447 (-1613 2649);
PAINT GREEN (-1613 2649);
FORCEPROP 2 LAST CDS_XR_PAGE_TITLE CR-252 : @S9S_MB_2U_LIB.S9S_MB_2U(SCH_1):PAGE252
J 0
(-5740 7850);
DISPLAY 0.638298 (-5740 7850);
PAINT PINK (-5740 7850);
DISPLAY INVISIBLE (-5740 7850);
FORCEPROP 2 LAST CDS_LIB pure_quanta
J 0
(2150 2600);
DISPLAY INVISIBLE (2150 2600);
FORCEPROP 1 LAST CDS_LMAN_SYM_OUTLINE -9475,6775,100,-125
J 0
(2150 2600);
DISPLAY 0.468085 (2150 2600);
PAINT GREEN (2150 2600);
DISPLAY INVISIBLE (2150 2600);
FORCEPROP 2 LAST PAGE_BORDER TRUE
J 0
(-5740 7850);
DISPLAY 0.638298 (-5740 7850);
PAINT PINK (-5740 7850);
DISPLAY INVISIBLE (-5740 7850);
FORCEPROP 1 LAST COMMENT_BODY TRUE
J 0
(2162 2587);
DISPLAY 0.978723 (2162 2587);
PAINT GREEN (2162 2587);
DISPLAY INVISIBLE (2162 2587);
WIRE 16 -1 (1950 8450)(1950 8575);
WIRE 16 -1 (1950 8450)(1450 8450);
WIRE 16 -1 (1975 7125)(1975 7225);
WIRE 16 -1 (1975 7125)(1425 7125);
WIRE 16 -1 (-2750 8450)(-2750 8550);
WIRE 16 -1 (-2750 8450)(-3300 8450);
WIRE 16 -1 (-2775 7125)(-2775 7200);
WIRE 16 -1 (-2775 7125)(-3275 7125);
WIRE 16 -1 (-2725 5900)(-2725 6025);
WIRE 16 -1 (-2725 5900)(-3225 5900);
WIRE 16 -1 (400 4825)(400 4625);
WIRE 16 -1 (375 5950)(375 5750);
WIRE 16 -1 (-2775 4575)(-2775 4675);
WIRE 16 -1 (-2775 4575)(-3275 4575);
WIRE 16 -1 (450 3575)(450 3400);
WIRE 16 -1 (-1000 7875)(-1000 7975);
WIRE 16 -1 (-1000 6550)(-1000 6650);
WIRE 16 -1 (-5775 7875)(-5775 7975);
WIRE 16 -1 (-5775 6550)(-5775 6650);
WIRE 16 -1 (-5775 5325)(-5775 5425);
WIRE 16 -1 (-5775 4000)(-5775 4100);
WIRE 16 -1 (-1725 5750)(-1725 5550);
WIRE 16 -1 (-1275 5750)(-1725 5750);
WIRE 16 -1 (-1700 4625)(-1700 4425);
WIRE 16 -1 (-1250 4625)(-1700 4625);
WIRE 16 -1 (-1775 3400)(-1775 3200);
WIRE 16 -1 (-1325 3400)(-1775 3400);
WIRE 16 -1 (-125 5750)(-975 5750);
FORCEPROP 2 LAST SIG_NAME LED_P5V_AUX
J 0
(-785 5760);
DISPLAY 0.723404 (-785 5760);
WIRE 16 -1 (75 5750)(375 5750);
WIRE 16 -1 (-100 4625)(-950 4625);
FORCEPROP 2 LAST SIG_NAME LED_P5V
J 0
(-760 4635);
DISPLAY 0.723404 (-760 4635);
WIRE 16 -1 (100 4625)(400 4625);
WIRE 74 -1 (100 4100)(-2050 4100);
WIRE 74 -1 (100 3900)(100 4100);
WIRE 74 -1 (-2050 4100)(-2050 3900);
WIRE 74 -1 (-2050 3900)(100 3900);
WIRE 74 -1 (75 5275)(-2075 5275);
WIRE 74 -1 (75 5075)(75 5275);
WIRE 74 -1 (-2075 5275)(-2075 5075);
WIRE 74 -1 (-2075 5075)(75 5075);
WIRE 74 -1 (75 6400)(-2075 6400);
WIRE 74 -1 (75 6200)(75 6400);
WIRE 74 -1 (-2075 6400)(-2075 6200);
WIRE 74 -1 (-2075 6200)(75 6200);
WIRE 16 -1 (-1000 7050)(-1000 7125);
FORCEPROP 2 LAST SIG_NAME LED_PWRGD_PS_PWROK_PLD_D
J 0
(-1085 7150);
DISPLAY 0.723404 (-1085 7150);
WIRE 16 -1 (-1000 7125)(-125 7125);
WIRE 74 -1 (250 7650)(-2075 7650);
WIRE 74 -1 (250 7450)(250 7650);
WIRE 74 -1 (-2075 7650)(-2075 7450);
WIRE 74 -1 (-2075 7450)(250 7450);
WIRE 16 -1 (-1250 6800)(-2100 6800);
FORCEPROP 2 LAST SIG_NAME PWRGD_PS_PWROK_PLD
J 0
(-2035 6810);
DISPLAY 0.723404 (-2035 6810);
WIRE 74 -1 (-4100 5100)(-6850 5100);
WIRE 74 -1 (-4100 4900)(-4100 5100);
WIRE 74 -1 (-6850 5100)(-6850 4900);
WIRE 74 -1 (-6850 4900)(-4100 4900);
WIRE 16 -1 (-4575 4575)(-3475 4575);
FORCEPROP 2 LAST SIG_NAME LED_FM_PCH_SLP_S4_N
J 0
(-4335 4585);
DISPLAY 0.723404 (-4335 4585);
WIRE 16 -1 (-5775 4500)(-5775 4575);
FORCEPROP 2 LAST SIG_NAME LED_FM_PCH_SLP_S4_N_D
J 0
(-5710 4585);
DISPLAY 0.723404 (-5710 4585);
WIRE 16 -1 (-5775 4575)(-4875 4575);
WIRE 16 -1 (-5775 5825)(-5775 5900);
WIRE 16 -1 (-5775 5900)(-4900 5900);
FORCEPROP 2 LAST SIG_NAME LED_RST_RSMRST_PLD_R_N_D
J 0
(-5760 5910);
DISPLAY 0.723404 (-5760 5910);
WIRE 74 -1 (-4450 6425)(-6850 6425);
WIRE 74 -1 (-4450 6225)(-4450 6425);
WIRE 74 -1 (-6850 6425)(-6850 6225);
WIRE 74 -1 (-6850 6225)(-4450 6225);
WIRE 16 -1 (-5775 7050)(-5775 7125);
FORCEPROP 2 LAST SIG_NAME LED_PWRGD_P1V05_PCH_AUX_D
J 0
(-5810 7135);
DISPLAY 0.723404 (-5810 7135);
WIRE 16 -1 (-5775 7125)(-4900 7125);
WIRE 74 -1 (-4600 7650)(-6850 7650);
WIRE 74 -1 (-4600 7450)(-4600 7650);
WIRE 74 -1 (-6850 7650)(-6850 7450);
WIRE 74 -1 (-6850 7450)(-4600 7450);
WIRE 16 -1 (-6025 6800)(-6875 6800);
FORCEPROP 2 LAST SIG_NAME PWRGD_P1V05_PCH_AUX
J 0
(-6735 6810);
DISPLAY 0.723404 (-6735 6810);
WIRE 74 -1 (-4600 8975)(-6850 8975);
WIRE 74 -1 (-4600 8775)(-4600 8975);
WIRE 74 -1 (-6850 8975)(-6850 8775);
WIRE 74 -1 (-6850 8775)(-4600 8775);
WIRE 16 -1 (-5775 8375)(-5775 8450);
FORCEPROP 2 LAST SIG_NAME LED_PWRGD_P1V8_PCH_AUX_D
J 0
(-5785 8460);
DISPLAY 0.723404 (-5785 8460);
WIRE 16 -1 (-5775 8450)(-4900 8450);
WIRE 16 -1 (-6025 5575)(-6875 5575);
FORCEPROP 2 LAST SIG_NAME RST_RSMRST_PLD_R_N
J 0
(-6835 5585);
DISPLAY 0.723404 (-6835 5585);
WIRE 16 -1 (-6025 8125)(-6875 8125);
FORCEPROP 2 LAST SIG_NAME PWRGD_P1V8_PCH_AUX
J 0
(-6735 8135);
DISPLAY 0.723404 (-6735 8135);
WIRE 16 -1 (-1250 8125)(-2100 8125);
FORCEPROP 2 LAST SIG_NAME FM_PCH_SLP_S3_N
J 0
(-2035 8135);
DISPLAY 0.723404 (-2035 8135);
WIRE 74 -1 (250 8975)(-2075 8975);
WIRE 74 -1 (250 8775)(250 8975);
WIRE 74 -1 (-2075 8975)(-2075 8775);
WIRE 74 -1 (-2075 8775)(250 8775);
WIRE 16 -1 (175 8450)(1250 8450);
FORCEPROP 2 LAST SIG_NAME LED_FM_PCH_SLP_S3_N
J 0
(240 8450);
DISPLAY 0.723404 (240 8450);
WIRE 16 -1 (-6025 4250)(-6875 4250);
FORCEPROP 2 LAST SIG_NAME FM_PCH_SLP_S4_N
J 0
(-6710 4260);
DISPLAY 0.723404 (-6710 4260);
WIRE 16 -1 (-4600 8450)(-3500 8450);
FORCEPROP 2 LAST SIG_NAME LED_PWRGD_P1V8_PCH_AUX
J 0
(-4435 8460);
DISPLAY 0.723404 (-4435 8460);
WIRE 16 -1 (-4600 5900)(-3425 5900);
FORCEPROP 2 LAST SIG_NAME LED_RST_RSMRST_PLD_R_N
J 0
(-4435 5910);
DISPLAY 0.723404 (-4435 5910);
WIRE 16 -1 (-1000 8450)(-125 8450);
WIRE 16 -1 (-1000 8375)(-1000 8450);
FORCEPROP 2 LAST SIG_NAME LED_FM_PCH_SLP_S3_N_D
J 0
(-935 8460);
DISPLAY 0.723404 (-935 8460);
WIRE 16 -1 (175 7125)(1225 7125);
FORCEPROP 2 LAST SIG_NAME LED_PWRGD_PS_PWROK_PLD
J 0
(240 7150);
DISPLAY 0.723404 (240 7150);
WIRE 16 -1 (-4600 7125)(-3475 7125);
FORCEPROP 2 LAST SIG_NAME LED_PWRGD_P1V05_PCH_AUX
J 0
(-4435 7135);
DISPLAY 0.723404 (-4435 7135);
WIRE 16 -1 (-175 3400)(-1025 3400);
FORCEPROP 2 LAST SIG_NAME LED_P3V3
J 0
(-835 3410);
DISPLAY 0.723404 (-835 3410);
WIRE 16 -1 (25 3400)(450 3400);
FORCENOTE
P5V          1 = ON
(-1950 5150) 0;
DISPLAY LEFT (-1950 5150);
DISPLAY 1.276596 (-1950 5150);
PAINT WHITE (-1950 5150);
FORCENOTE
FM_PCH_SLP_S3         1 = ON
(-1950 8850) 0;
DISPLAY LEFT (-1950 8850);
DISPLAY 1.276596 (-1950 8850);
PAINT WHITE (-1950 8850);
FORCENOTE
FM_PCH_SLP_S4          1 = ON
(-6725 4975) 0;
DISPLAY LEFT (-6725 4975);
DISPLAY 1.276596 (-6725 4975);
PAINT WHITE (-6725 4975);
FORCENOTE
PWRGD_P1V8_PCH_AUX          1 = ON
(-6725 8850) 0;
DISPLAY LEFT (-6725 8850);
DISPLAY 1.276596 (-6725 8850);
PAINT WHITE (-6725 8850);
FORCENOTE
20210705 MODIFY FOR GT
(-5025 9075) 0;
DISPLAY LEFT (-5025 9075);
DISPLAY 2.510638 (-5025 9075);
PAINT PINK (-5025 9075);
FORCENOTE
PWRGD_P1V05_PCH_AUX          1 = ON
(-6725 7525) 0;
DISPLAY LEFT (-6725 7525);
DISPLAY 1.276596 (-6725 7525);
PAINT WHITE (-6725 7525);
FORCENOTE
RST_RSMRST_PLD_R_N          1 = ON
(-6725 6300) 0;
DISPLAY LEFT (-6725 6300);
DISPLAY 1.276596 (-6725 6300);
PAINT WHITE (-6725 6300);
FORCENOTE
PWRGD_PS_PWROK          1 = ON
(-1950 7525) 0;
DISPLAY LEFT (-1950 7525);
DISPLAY 1.276596 (-1950 7525);
PAINT WHITE (-1950 7525);
FORCENOTE
P5V_AUX          1 = ON
(-1950 6275) 0;
DISPLAY LEFT (-1950 6275);
DISPLAY 1.276596 (-1950 6275);
PAINT WHITE (-1950 6275);
FORCENOTE
P3V3          1 = ON
(-1925 3975) 0;
DISPLAY LEFT (-1925 3975);
DISPLAY 1.276596 (-1925 3975);
PAINT WHITE (-1925 3975);
QUIT
